(kicad_pcb
	(version 20260206)
	(generator "pcbnew")
	(generator_version "10.0")
	(general
		(thickness 1.6)
		(legacy_teardrops no)
	)
	(paper "A4")
	(title_block
		(title "netronome-mezz — pcbd0082-001_rev01_jul9_a.brd")
		(comment 1 "Open CloudServer (Microsoft) / footprints 16-24 of 714")
	)
	(layers
		(0 "F.Cu" signal "TOP")
		(4 "In1.Cu" signal "02_GND")
		(6 "In2.Cu" signal "03_SIG")
		(8 "In3.Cu" signal "04_SIG")
		(10 "In4.Cu" signal "05_GND")
		(12 "In5.Cu" signal "06_PWR1")
		(14 "In6.Cu" signal "07_SIG")
		(16 "In7.Cu" signal "08_SIG")
		(18 "In8.Cu" signal "09_GND")
		(2 "B.Cu" signal "BOTTOM")
		(9 "F.Adhes" user "F.Adhesive")
		(11 "B.Adhes" user "B.Adhesive")
		(13 "F.Paste" user "Package Geometry/Pastemask Top")
		(15 "B.Paste" user "Package Geometry/Pastemask Bottom")
		(5 "F.SilkS" user "Ref Des/Silkscreen Top")
		(7 "B.SilkS" user "Ref Des/Silkscreen Bottom")
		(1 "F.Mask" user "Board Geometry/Soldermask Top")
		(3 "B.Mask" user "Board Geometry/Soldermask Bottom")
		(17 "Dwgs.User" user "User.Drawings")
		(19 "Cmts.User" user "User.Comments")
		(21 "Eco1.User" user "User.Eco1")
		(23 "Eco2.User" user "User.Eco2")
		(25 "Edge.Cuts" user "Board Geometry/Outline")
		(27 "Margin" user)
		(31 "F.CrtYd" user "Package Geometry/Place Bound Top")
		(29 "B.CrtYd" user "Package Geometry/Place Bound Bottom")
		(35 "F.Fab" user "Ref Des/Assembly Top")
		(33 "B.Fab" user "Ref Des/Assembly Bottom")
		(45 "User.4" user "COMPVAL_TYPE_BOTTOM")
	)
	(footprint ""
		(layer "F.Cu")
		(at 33.6042 42.545 90)
		(property "Reference" "C35"
			(at 0 0 90)
			(layer "F.SilkS")
			(hide yes)
			(effects
				(font
					(size 1.27 1.27)
				)
			)
		)
		(property "Value" "6800PF"
			(at -0.091846 0.2921 180)
			(unlocked yes)
			(layer "F.Fab")
			(hide yes)
			(effects
				(font
					(size 0.7874 0.5842)
					(thickness 0.2032)
				)
				(justify left)
			)
		)
		(property "Device Type" "CAPC0079"
			(at -0.091846 0.2921 180)
			(unlocked yes)
			(layer "F.Fab")
			(hide yes)
			(effects
				(font
					(size 0.7874 0.5842)
					(thickness 0.2032)
				)
				(justify left)
			)
		)
		(duplicate_pad_numbers_are_jumpers no)
		(fp_poly
			(pts
				(xy 0.635 1.0668) (xy 0.635 -1.0668) (xy -0.635 -1.0668) (xy -0.635 1.0668)
			)
			(stroke
				(width 0)
				(type default)
			)
			(fill no)
			(layer "F.CrtYd")
		)
		(fp_line
			(start 0.254 -0.508)
			(end 0.254 0.508)
			(stroke
				(width 0.0254)
				(type default)
			)
			(layer "F.Fab")
		)
		(fp_line
			(start -0.254 -0.508)
			(end 0.254 -0.508)
			(stroke
				(width 0.0254)
				(type default)
			)
			(layer "F.Fab")
		)
		(fp_line
			(start 0.254 0.508)
			(end -0.254 0.508)
			(stroke
				(width 0.0254)
				(type default)
			)
			(layer "F.Fab")
		)
		(fp_line
			(start -0.254 0.508)
			(end -0.254 -0.508)
			(stroke
				(width 0.0254)
				(type default)
			)
			(layer "F.Fab")
		)
		(pad "1" smd rect
			(at 0 -0.4191 90)
			(size 0.508 0.5334)
			(layers "F.Cu" "F.Mask" "F.Paste")
			(net "10N2528")
		)
		(pad "2" smd rect
			(at 0 0.4191 90)
			(size 0.508 0.5334)
			(layers "F.Cu" "F.Mask" "F.Paste")
			(net "NFP_VDD_CORE_TCOMPA")
		)
		(zone
			(layer "F.Cu")
			(hatch none 0.5)
			(connect_pads
				(clearance 0)
			)
			(min_thickness 0.25)
			(keepout
				(tracks not_allowed)
				(vias allowed)
				(pads allowed)
				(copperpour not_allowed)
				(footprints allowed)
			)
			(placement
				(enabled no)
				(sheetname "")
			)
			(fill
				(thermal_gap 0.5)
				(thermal_bridge_width 0.5)
				(island_removal_mode 0)
			)
			(polygon
				(pts
					(xy 33.5788 42.5196) (xy 33.6296 42.5196) (xy 33.6296 42.5704) (xy 33.5788 42.5704)
				)
			)
		)
	)
	(footprint ""
		(layer "F.Cu")
		(at 59.055 53.721)
		(property "Reference" "C181"
			(at -1.651 2.18567 0)
			(unlocked yes)
			(layer "F.SilkS")
			(effects
				(font
					(size 0.7874 0.5842)
					(thickness 0.127)
				)
				(justify left)
			)
		)
		(property "Value" ""
			(at 0 0 0)
			(layer "F.Fab")
			(effects
				(font
					(size 1.27 1.27)
				)
			)
		)
		(duplicate_pad_numbers_are_jumpers no)
		(fp_arc
			(start -0.381 -0.336017)
			(mid -0.20901 -0.463015)
			(end 0 -0.508)
			(stroke
				(width 0.2032)
				(type default)
			)
			(layer "F.SilkS")
		)
		(fp_arc
			(start 0 -0.508)
			(mid 0.209008 -0.463011)
			(end 0.381 -0.336017)
			(stroke
				(width 0.2032)
				(type default)
			)
			(layer "F.SilkS")
		)
		(fp_arc
			(start 0 0.508)
			(mid -0.209 0.463015)
			(end -0.381 0.336042)
			(stroke
				(width 0.2032)
				(type default)
			)
			(layer "F.SilkS")
		)
		(fp_arc
			(start 0.381 0.335991)
			(mid 0.209012 0.462996)
			(end 0 0.508)
			(stroke
				(width 0.2032)
				(type default)
			)
			(layer "F.SilkS")
		)
		(fp_circle
			(center 0 0)
			(end 0.508 0)
			(stroke
				(width 0.2032)
				(type default)
			)
			(fill no)
			(layer "F.SilkS")
		)
		(fp_poly
			(pts
				(xy -2.286 1.778) (xy -2.286 -1.778) (xy 2.286 -1.778) (xy 2.286 1.778)
			)
			(stroke
				(width 0)
				(type default)
			)
			(fill no)
			(layer "F.CrtYd")
		)
		(fp_line
			(start -1.524 -1.27)
			(end 1.524 -1.27)
			(stroke
				(width 0.0254)
				(type default)
			)
			(layer "F.Fab")
		)
		(fp_line
			(start -1.524 1.27)
			(end -1.524 -1.27)
			(stroke
				(width 0.0254)
				(type default)
			)
			(layer "F.Fab")
		)
		(fp_line
			(start 1.524 -1.27)
			(end 1.524 1.27)
			(stroke
				(width 0.0254)
				(type default)
			)
			(layer "F.Fab")
		)
		(fp_line
			(start 1.524 1.27)
			(end -1.524 1.27)
			(stroke
				(width 0.0254)
				(type default)
			)
			(layer "F.Fab")
		)
		(pad "1" smd rect
			(at -1.4224 0 90)
			(size 2.7432 1.3716)
			(layers "F.Cu" "F.Mask" "F.Paste")
			(net "VDD_5.0V")
		)
		(pad "2" smd rect
			(at 1.4224 0 90)
			(size 2.7432 1.3716)
			(layers "F.Cu" "F.Mask" "F.Paste")
			(net "GND")
		)
	)
	(footprint ""
		(layer "F.Cu")
		(at 43.307 51.816)
		(property "Reference" "C248"
			(at 0 0 0)
			(layer "F.SilkS")
			(hide yes)
			(effects
				(font
					(size 1.27 1.27)
				)
			)
		)
		(property "Value" "0.1UF"
			(at -0.091846 0.2921 90)
			(unlocked yes)
			(layer "F.Fab")
			(hide yes)
			(effects
				(font
					(size 0.7874 0.5842)
					(thickness 0.2032)
				)
				(justify left)
			)
		)
		(property "Device Type" "CAPC0073"
			(at -0.091846 0.2921 90)
			(unlocked yes)
			(layer "F.Fab")
			(hide yes)
			(effects
				(font
					(size 0.7874 0.5842)
					(thickness 0.2032)
				)
				(justify left)
			)
		)
		(duplicate_pad_numbers_are_jumpers no)
		(fp_poly
			(pts
				(xy 0.635 1.0668) (xy 0.635 -1.0668) (xy -0.635 -1.0668) (xy -0.635 1.0668)
			)
			(stroke
				(width 0)
				(type default)
			)
			(fill no)
			(layer "F.CrtYd")
		)
		(fp_line
			(start -0.254 -0.508)
			(end 0.254 -0.508)
			(stroke
				(width 0.0254)
				(type default)
			)
			(layer "F.Fab")
		)
		(fp_line
			(start -0.254 0.508)
			(end -0.254 -0.508)
			(stroke
				(width 0.0254)
				(type default)
			)
			(layer "F.Fab")
		)
		(fp_line
			(start 0.254 -0.508)
			(end 0.254 0.508)
			(stroke
				(width 0.0254)
				(type default)
			)
			(layer "F.Fab")
		)
		(fp_line
			(start 0.254 0.508)
			(end -0.254 0.508)
			(stroke
				(width 0.0254)
				(type default)
			)
			(layer "F.Fab")
		)
		(pad "1" smd rect
			(at 0 -0.4191)
			(size 0.508 0.5334)
			(layers "F.Cu" "F.Mask" "F.Paste")
			(net "EXT_12.0V_THRESHOLD")
		)
		(pad "2" smd rect
			(at 0 0.4191)
			(size 0.508 0.5334)
			(layers "F.Cu" "F.Mask" "F.Paste")
			(net "GND")
		)
		(zone
			(layer "F.Cu")
			(hatch none 0.5)
			(connect_pads
				(clearance 0)
			)
			(min_thickness 0.25)
			(keepout
				(tracks not_allowed)
				(vias allowed)
				(pads allowed)
				(copperpour not_allowed)
				(footprints allowed)
			)
			(placement
				(enabled no)
				(sheetname "")
			)
			(fill
				(thermal_gap 0.5)
				(thermal_bridge_width 0.5)
				(island_removal_mode 0)
			)
			(polygon
				(pts
					(xy 43.3324 51.7906) (xy 43.3324 51.8414) (xy 43.2816 51.8414) (xy 43.2816 51.7906)
				)
			)
		)
	)
	(footprint ""
		(layer "F.Cu")
		(at 6.9342 38.608)
		(property "Reference" "TP20"
			(at -1.24333 3.937 90)
			(unlocked yes)
			(layer "F.SilkS")
			(effects
				(font
					(size 0.7874 0.5842)
					(thickness 0.127)
				)
				(justify left)
			)
		)
		(property "Value" "*"
			(at -0.4826 -0.14732 0)
			(unlocked yes)
			(layer "F.Fab")
			(hide yes)
			(effects
				(font
					(size 1.27 0.9652)
					(thickness 0.000001)
				)
				(justify left)
			)
		)
		(property "Device Type" "TP_SMALL"
			(at -0.4826 -0.14732 0)
			(unlocked yes)
			(layer "F.Fab")
			(hide yes)
			(effects
				(font
					(size 1.27 0.9652)
					(thickness 0.000001)
				)
				(justify left)
			)
		)
		(duplicate_pad_numbers_are_jumpers no)
		(fp_line
			(start -0.8636 -0.8636)
			(end -0.8636 0.8636)
			(stroke
				(width 0.1524)
				(type default)
			)
			(layer "F.SilkS")
		)
		(fp_line
			(start -0.8636 0.8636)
			(end 0.8636 0.8636)
			(stroke
				(width 0.1524)
				(type default)
			)
			(layer "F.SilkS")
		)
		(fp_line
			(start 0.8636 -0.8636)
			(end -0.8636 -0.8636)
			(stroke
				(width 0.1524)
				(type default)
			)
			(layer "F.SilkS")
		)
		(fp_line
			(start 0.8636 0.8636)
			(end 0.8636 -0.8636)
			(stroke
				(width 0.1524)
				(type default)
			)
			(layer "F.SilkS")
		)
		(fp_poly
			(pts
				(xy -0.635 -0.635) (xy -0.635 0.635) (xy 0.635 0.635) (xy 0.635 -0.635)
			)
			(stroke
				(width 0)
				(type default)
			)
			(fill no)
			(layer "F.CrtYd")
		)
		(pad "1" smd rect
			(at 0 0)
			(size 1.27 1.27)
			(layers "F.Cu" "F.Mask" "F.Paste")
			(net "CPLD_GPIO_2")
		)
	)
	(footprint ""
		(layer "F.Cu")
		(at 41.91 49.3776 180)
		(property "Reference" "R122"
			(at 0 0 180)
			(layer "F.SilkS")
			(hide yes)
			(effects
				(font
					(size 1.27 1.27)
				)
			)
		)
		(property "Value" "100K"
			(at -0.148158 1.3462 270)
			(unlocked yes)
			(layer "F.Fab")
			(hide yes)
			(effects
				(font
					(size 1.27 0.9652)
					(thickness 0.000001)
				)
				(justify left)
			)
		)
		(property "Device Type" "REST0001"
			(at -0.148158 1.3462 270)
			(unlocked yes)
			(layer "F.Fab")
			(hide yes)
			(effects
				(font
					(size 1.27 0.9652)
					(thickness 0.000001)
				)
				(justify left)
			)
		)
		(duplicate_pad_numbers_are_jumpers no)
		(fp_poly
			(pts
				(xy 0.635 1.0668) (xy 0.635 -1.0668) (xy -0.635 -1.0668) (xy -0.635 1.0668)
			)
			(stroke
				(width 0)
				(type default)
			)
			(fill no)
			(layer "F.CrtYd")
		)
		(fp_line
			(start 0.254 0.508)
			(end -0.254 0.508)
			(stroke
				(width 0.0254)
				(type default)
			)
			(layer "F.Fab")
		)
		(fp_line
			(start 0.254 -0.508)
			(end 0.254 0.508)
			(stroke
				(width 0.0254)
				(type default)
			)
			(layer "F.Fab")
		)
		(fp_line
			(start -0.254 0.508)
			(end -0.254 -0.508)
			(stroke
				(width 0.0254)
				(type default)
			)
			(layer "F.Fab")
		)
		(fp_line
			(start -0.254 -0.508)
			(end 0.254 -0.508)
			(stroke
				(width 0.0254)
				(type default)
			)
			(layer "F.Fab")
		)
		(pad "1" smd rect
			(at 0 -0.4191 180)
			(size 0.508 0.5334)
			(layers "F.Cu" "F.Mask" "F.Paste")
			(net "EXT_12.0V_THRESHOLD")
		)
		(pad "2" smd rect
			(at 0 0.4191 180)
			(size 0.508 0.5334)
			(layers "F.Cu" "F.Mask" "F.Paste")
			(net "EXT_12.0V_PGOOD")
		)
		(zone
			(layer "F.Cu")
			(hatch none 0.5)
			(connect_pads
				(clearance 0)
			)
			(min_thickness 0.25)
			(keepout
				(tracks not_allowed)
				(vias allowed)
				(pads allowed)
				(copperpour not_allowed)
				(footprints allowed)
			)
			(placement
				(enabled no)
				(sheetname "")
			)
			(fill
				(thermal_gap 0.5)
				(thermal_bridge_width 0.5)
				(island_removal_mode 0)
			)
			(polygon
				(pts
					(xy 41.8846 49.403) (xy 41.8846 49.3522) (xy 41.9354 49.3522) (xy 41.9354 49.403)
				)
			)
		)
	)
	(footprint ""
		(layer "F.Cu")
		(at 27.559 43.561)
		(property "Reference" "R120"
			(at 0 0 0)
			(layer "F.SilkS")
			(hide yes)
			(effects
				(font
					(size 1.27 1.27)
				)
			)
		)
		(property "Value" "100K"
			(at -0.148158 1.3462 90)
			(unlocked yes)
			(layer "F.Fab")
			(hide yes)
			(effects
				(font
					(size 1.27 0.9652)
					(thickness 0.000001)
				)
				(justify left)
			)
		)
		(property "Device Type" "REST0001"
			(at -0.148158 1.3462 90)
			(unlocked yes)
			(layer "F.Fab")
			(hide yes)
			(effects
				(font
					(size 1.27 0.9652)
					(thickness 0.000001)
				)
				(justify left)
			)
		)
		(duplicate_pad_numbers_are_jumpers no)
		(fp_poly
			(pts
				(xy 0.635 1.0668) (xy 0.635 -1.0668) (xy -0.635 -1.0668) (xy -0.635 1.0668)
			)
			(stroke
				(width 0)
				(type default)
			)
			(fill no)
			(layer "F.CrtYd")
		)
		(fp_line
			(start -0.254 -0.508)
			(end 0.254 -0.508)
			(stroke
				(width 0.0254)
				(type default)
			)
			(layer "F.Fab")
		)
		(fp_line
			(start -0.254 0.508)
			(end -0.254 -0.508)
			(stroke
				(width 0.0254)
				(type default)
			)
			(layer "F.Fab")
		)
		(fp_line
			(start 0.254 -0.508)
			(end 0.254 0.508)
			(stroke
				(width 0.0254)
				(type default)
			)
			(layer "F.Fab")
		)
		(fp_line
			(start 0.254 0.508)
			(end -0.254 0.508)
			(stroke
				(width 0.0254)
				(type default)
			)
			(layer "F.Fab")
		)
		(pad "1" smd rect
			(at 0 -0.4191)
			(size 0.508 0.5334)
			(layers "F.Cu" "F.Mask" "F.Paste")
			(net "10N2383")
		)
		(pad "2" smd rect
			(at 0 0.4191)
			(size 0.508 0.5334)
			(layers "F.Cu" "F.Mask" "F.Paste")
			(net "10N2504")
		)
		(zone
			(layer "F.Cu")
			(hatch none 0.5)
			(connect_pads
				(clearance 0)
			)
			(min_thickness 0.25)
			(keepout
				(tracks not_allowed)
				(vias allowed)
				(pads allowed)
				(copperpour not_allowed)
				(footprints allowed)
			)
			(placement
				(enabled no)
				(sheetname "")
			)
			(fill
				(thermal_gap 0.5)
				(thermal_bridge_width 0.5)
				(island_removal_mode 0)
			)
			(polygon
				(pts
					(xy 27.5844 43.5356) (xy 27.5844 43.5864) (xy 27.5336 43.5864) (xy 27.5336 43.5356)
				)
			)
		)
	)
	(footprint ""
		(layer "F.Cu")
		(at 75.057 32.258 90)
		(property "Reference" "C219"
			(at -0.91567 -1.524 0)
			(unlocked yes)
			(layer "F.SilkS")
			(effects
				(font
					(size 0.7874 0.5842)
					(thickness 0.127)
				)
				(justify left)
			)
		)
		(property "Value" "1UF"
			(at -0.091846 0.2921 180)
			(unlocked yes)
			(layer "F.Fab")
			(hide yes)
			(effects
				(font
					(size 0.7874 0.5842)
					(thickness 0.2032)
				)
				(justify left)
			)
		)
		(property "Device Type" "CAPC0028"
			(at -0.091846 0.2921 180)
			(unlocked yes)
			(layer "F.Fab")
			(hide yes)
			(effects
				(font
					(size 0.7874 0.5842)
					(thickness 0.2032)
				)
				(justify left)
			)
		)
		(duplicate_pad_numbers_are_jumpers no)
		(fp_poly
			(pts
				(xy 0.635 1.0668) (xy 0.635 -1.0668) (xy -0.635 -1.0668) (xy -0.635 1.0668)
			)
			(stroke
				(width 0)
				(type default)
			)
			(fill no)
			(layer "F.CrtYd")
		)
		(fp_line
			(start 0.254 -0.508)
			(end 0.254 0.508)
			(stroke
				(width 0.0254)
				(type default)
			)
			(layer "F.Fab")
		)
		(fp_line
			(start -0.254 -0.508)
			(end 0.254 -0.508)
			(stroke
				(width 0.0254)
				(type default)
			)
			(layer "F.Fab")
		)
		(fp_line
			(start 0.254 0.508)
			(end -0.254 0.508)
			(stroke
				(width 0.0254)
				(type default)
			)
			(layer "F.Fab")
		)
		(fp_line
			(start -0.254 0.508)
			(end -0.254 -0.508)
			(stroke
				(width 0.0254)
				(type default)
			)
			(layer "F.Fab")
		)
		(pad "1" smd rect
			(at 0 -0.4191 90)
			(size 0.508 0.5334)
			(layers "F.Cu" "F.Mask" "F.Paste")
			(net "DDR_VDDQ")
		)
		(pad "2" smd rect
			(at 0 0.4191 90)
			(size 0.508 0.5334)
			(layers "F.Cu" "F.Mask" "F.Paste")
			(net "GND")
		)
		(zone
			(layer "F.Cu")
			(hatch none 0.5)
			(connect_pads
				(clearance 0)
			)
			(min_thickness 0.25)
			(keepout
				(tracks not_allowed)
				(vias allowed)
				(pads allowed)
				(copperpour not_allowed)
				(footprints allowed)
			)
			(placement
				(enabled no)
				(sheetname "")
			)
			(fill
				(thermal_gap 0.5)
				(thermal_bridge_width 0.5)
				(island_removal_mode 0)
			)
			(polygon
				(pts
					(xy 75.0316 32.2326) (xy 75.0824 32.2326) (xy 75.0824 32.2834) (xy 75.0316 32.2834)
				)
			)
		)
	)
	(footprint ""
		(layer "F.Cu")
		(at 26.67 41.275 90)
		(property "Reference" "R308"
			(at 0 0 90)
			(layer "F.SilkS")
			(hide yes)
			(effects
				(font
					(size 1.27 1.27)
				)
			)
		)
		(property "Value" "523K"
			(at -0.148158 1.3462 180)
			(unlocked yes)
			(layer "F.Fab")
			(hide yes)
			(effects
				(font
					(size 1.27 0.9652)
					(thickness 0.000001)
				)
				(justify left)
			)
		)
		(property "Device Type" "REST0291"
			(at -0.148158 1.3462 180)
			(unlocked yes)
			(layer "F.Fab")
			(hide yes)
			(effects
				(font
					(size 1.27 0.9652)
					(thickness 0.000001)
				)
				(justify left)
			)
		)
		(duplicate_pad_numbers_are_jumpers no)
		(fp_poly
			(pts
				(xy 0.635 1.0668) (xy 0.635 -1.0668) (xy -0.635 -1.0668) (xy -0.635 1.0668)
			)
			(stroke
				(width 0)
				(type default)
			)
			(fill no)
			(layer "F.CrtYd")
		)
		(fp_line
			(start 0.254 -0.508)
			(end 0.254 0.508)
			(stroke
				(width 0.0254)
				(type default)
			)
			(layer "F.Fab")
		)
		(fp_line
			(start -0.254 -0.508)
			(end 0.254 -0.508)
			(stroke
				(width 0.0254)
				(type default)
			)
			(layer "F.Fab")
		)
		(fp_line
			(start 0.254 0.508)
			(end -0.254 0.508)
			(stroke
				(width 0.0254)
				(type default)
			)
			(layer "F.Fab")
		)
		(fp_line
			(start -0.254 0.508)
			(end -0.254 -0.508)
			(stroke
				(width 0.0254)
				(type default)
			)
			(layer "F.Fab")
		)
		(pad "1" smd rect
			(at 0 -0.4191 90)
			(size 0.508 0.5334)
			(layers "F.Cu" "F.Mask" "F.Paste")
			(net "GND")
		)
		(pad "2" smd rect
			(at 0 0.4191 90)
			(size 0.508 0.5334)
			(layers "F.Cu" "F.Mask" "F.Paste")
			(net "10N2399")
		)
		(zone
			(layer "F.Cu")
			(hatch none 0.5)
			(connect_pads
				(clearance 0)
			)
			(min_thickness 0.25)
			(keepout
				(tracks not_allowed)
				(vias allowed)
				(pads allowed)
				(copperpour not_allowed)
				(footprints allowed)
			)
			(placement
				(enabled no)
				(sheetname "")
			)
			(fill
				(thermal_gap 0.5)
				(thermal_bridge_width 0.5)
				(island_removal_mode 0)
			)
			(polygon
				(pts
					(xy 26.6446 41.2496) (xy 26.6954 41.2496) (xy 26.6954 41.3004) (xy 26.6446 41.3004)
				)
			)
		)
	)
	(footprint ""
		(layer "F.Cu")
		(at 11.303 40.894 -90)
		(property "Reference" "C131"
			(at -0.98933 1.651 0)
			(unlocked yes)
			(layer "F.SilkS")
			(effects
				(font
					(size 0.7874 0.5842)
					(thickness 0.127)
				)
				(justify left)
			)
		)
		(property "Value" "10UF"
			(at -0.148158 1.7526 0)
			(unlocked yes)
			(layer "F.Fab")
			(hide yes)
			(effects
				(font
					(size 1.27 0.9652)
					(thickness 0.000001)
				)
				(justify left)
			)
		)
		(property "Device Type" "CAPC0058"
			(at -0.148158 1.7526 0)
			(unlocked yes)
			(layer "F.Fab")
			(hide yes)
			(effects
				(font
					(size 1.27 0.9652)
					(thickness 0.000001)
				)
				(justify left)
			)
		)
		(duplicate_pad_numbers_are_jumpers no)
		(fp_circle
			(center 0 0)
			(end 0 -0.127)
			(stroke
				(width 0.2032)
				(type default)
			)
			(fill no)
			(layer "F.SilkS")
		)
		(fp_poly
			(pts
				(xy 0.7874 -1.6637) (xy -0.7874 -1.6637) (xy -0.7874 1.6637) (xy 0.7874 1.6637)
			)
			(stroke
				(width 0)
				(type default)
			)
			(fill no)
			(layer "F.CrtYd")
		)
		(fp_line
			(start -0.4064 0.8128)
			(end -0.4064 -0.7874)
			(stroke
				(width 0.0254)
				(type default)
			)
			(layer "F.Fab")
		)
		(fp_line
			(start 0.4064 0.8128)
			(end -0.4064 0.8128)
			(stroke
				(width 0.0254)
				(type default)
			)
			(layer "F.Fab")
		)
		(fp_line
			(start -0.4064 -0.7874)
			(end 0.4064 -0.7874)
			(stroke
				(width 0.0254)
				(type default)
			)
			(layer "F.Fab")
		)
		(fp_line
			(start 0.4064 -0.7874)
			(end 0.4064 0.8128)
			(stroke
				(width 0.0254)
				(type default)
			)
			(layer "F.Fab")
		)
		(pad "1" smd rect
			(at 0 -0.8001 270)
			(size 0.8636 0.9652)
			(layers "F.Cu" "F.Mask" "F.Paste")
			(net "VDD_5.0V")
		)
		(pad "2" smd rect
			(at 0 0.8001 270)
			(size 0.8636 0.9652)
			(layers "F.Cu" "F.Mask" "F.Paste")
			(net "GND")
		)
	)
)
